# S9S_MB_2U (Grand Teton) — schematic netlist excerpt (pin names and nets, part order shuffled) for the footprints in the layout excerpt that follows; sources: Cadence DE-HDL packaged netlist, KiCad conversion of 03242023_DA0F0TMBIJ0_F0T_Motherboard_J_brd_V01_OCP.brd

R4740  Q_RES  4.7K 5% CHIP  pkg 0402LF  page 144 : A = P3V3_AUX ; B = PRSNT_CABLE_SWB_B1_ISO_N
R2948  Q_RES  4.7K 5% EMPTY  pkg 0402LF  page 246 : A = FM_GPU_HSC_EN_BUF_R ; B = GND

(kicad_pcb
	(version 20260206)
	(generator "pcbnew")
	(generator_version "10.0")
	(general
		(thickness 1.6)
		(legacy_teardrops no)
	)
	(paper "A4")
	(title_block
		(title "03242023_DA0F0TMBIJ0_F0T_Motherboard_J_brd_V01_OCP.brd")
		(comment 1 "Grand Teton / footprints 1706-1707 of 6105")
	)
	(layers
		(0 "F.Cu" signal "TOP")
		(4 "In1.Cu" signal "GND")
		(6 "In2.Cu" signal "IN1")
		(8 "In3.Cu" signal "GND1")
		(10 "In4.Cu" signal "IN2")
		(12 "In5.Cu" signal "GND2")
		(14 "In6.Cu" signal "IN3")
		(16 "In7.Cu" signal "GND3")
		(18 "In8.Cu" signal "VCC")
		(20 "In9.Cu" signal "VCC1")
		(22 "In10.Cu" signal "GND4")
		(24 "In11.Cu" signal "IN4")
		(26 "In12.Cu" signal "GND5")
		(28 "In13.Cu" signal "IN5")
		(30 "In14.Cu" signal "GND6")
		(32 "In15.Cu" signal "IN6")
		(34 "In16.Cu" signal "GND7")
		(2 "B.Cu" signal "BOTTOM")
		(9 "F.Adhes" user "F.Adhesive")
		(11 "B.Adhes" user "B.Adhesive")
		(13 "F.Paste" user "Package Geometry/Pastemask Top")
		(15 "B.Paste" user "Package Geometry/Pastemask Bottom")
		(5 "F.SilkS" user "Ref Des/Silkscreen Top")
		(7 "B.SilkS" user "Ref Des/Silkscreen Bottom")
		(1 "F.Mask" user "Board Geometry/Soldermask Top")
		(3 "B.Mask" user "Board Geometry/Soldermask Bottom")
		(17 "Dwgs.User" user "User.Drawings")
		(19 "Cmts.User" user "User.Comments")
		(21 "Eco1.User" user "User.Eco1")
		(23 "Eco2.User" user "User.Eco2")
		(25 "Edge.Cuts" user "Board Geometry/Outline")
		(27 "Margin" user)
		(31 "F.CrtYd" user "Package Geometry/Place Bound Top")
		(29 "B.CrtYd" user "Package Geometry/Place Bound Bottom")
		(35 "F.Fab" user "Ref Des/Assembly Top")
		(33 "B.Fab" user "Ref Des/Assembly Bottom")
	)
	(footprint ""
		(layer "F.Cu")
		(at 191.988186 -429.41113 -90)
		(property "Reference" "R2948"
			(at 0 0 270)
			(layer "F.SilkS")
			(hide yes)
			(effects
				(font
					(size 1.27 1.27)
				)
			)
		)
		(property "Value" ""
			(at 0 0 270)
			(layer "F.Fab")
			(effects
				(font
					(size 1.27 1.27)
				)
			)
		)
		(duplicate_pad_numbers_are_jumpers no)
		(fp_line
			(start -0.7874 0.4064)
			(end -0.7874 -0.4064)
			(stroke
				(width 0.1524)
				(type default)
			)
			(layer "F.SilkS")
		)
		(fp_line
			(start 0.7874 0.4064)
			(end -0.7874 0.4064)
			(stroke
				(width 0.1524)
				(type default)
			)
			(layer "F.SilkS")
		)
		(fp_line
			(start -0.7874 -0.4064)
			(end 0.7874 -0.4064)
			(stroke
				(width 0.1524)
				(type default)
			)
			(layer "F.SilkS")
		)
		(fp_line
			(start 0.7874 -0.4064)
			(end 0.7874 0.4064)
			(stroke
				(width 0.1524)
				(type default)
			)
			(layer "F.SilkS")
		)
		(fp_line
			(start -0.67945 0.3048)
			(end -0.67945 -0.305054)
			(stroke
				(width 0.1)
				(type default)
			)
			(layer "F.Fab")
		)
		(fp_line
			(start -0.12065 0.3048)
			(end -0.67945 0.3048)
			(stroke
				(width 0.1)
				(type default)
			)
			(layer "F.Fab")
		)
		(fp_line
			(start 0.120396 0.3048)
			(end 0.120396 0.2794)
			(stroke
				(width 0.1)
				(type default)
			)
			(layer "F.Fab")
		)
		(fp_line
			(start 0.67945 0.3048)
			(end 0.120396 0.3048)
			(stroke
				(width 0.1)
				(type default)
			)
			(layer "F.Fab")
		)
		(fp_line
			(start -0.12065 0.2794)
			(end -0.12065 0.3048)
			(stroke
				(width 0.1)
				(type default)
			)
			(layer "F.Fab")
		)
		(fp_line
			(start 0.120396 0.2794)
			(end -0.12065 0.2794)
			(stroke
				(width 0.1)
				(type default)
			)
			(layer "F.Fab")
		)
		(fp_line
			(start -0.12065 -0.2794)
			(end 0.12065 -0.2794)
			(stroke
				(width 0.1)
				(type default)
			)
			(layer "F.Fab")
		)
		(fp_line
			(start 0.12065 -0.2794)
			(end 0.12065 -0.3048)
			(stroke
				(width 0.1)
				(type default)
			)
			(layer "F.Fab")
		)
		(fp_line
			(start 0.12065 -0.3048)
			(end 0.67945 -0.3048)
			(stroke
				(width 0.1)
				(type default)
			)
			(layer "F.Fab")
		)
		(fp_line
			(start 0.67945 -0.3048)
			(end 0.67945 0.3048)
			(stroke
				(width 0.1)
				(type default)
			)
			(layer "F.Fab")
		)
		(fp_line
			(start -0.67945 -0.305054)
			(end -0.12065 -0.305054)
			(stroke
				(width 0.1)
				(type default)
			)
			(layer "F.Fab")
		)
		(fp_line
			(start -0.12065 -0.305054)
			(end -0.12065 -0.2794)
			(stroke
				(width 0.1)
				(type default)
			)
			(layer "F.Fab")
		)
		(pad "1" smd circle
			(at -0.40005 0 270)
			(size 0 0)
			(layers "F.Cu" "F.Mask" "F.Paste")
			(net "FM_GPU_HSC_EN_BUF_R")
		)
		(pad "2" smd circle
			(at 0.40005 0 270)
			(size 0 0)
			(layers "F.Cu" "F.Mask" "F.Paste")
			(net "GND")
		)
	)
	(footprint ""
		(layer "F.Cu")
		(at 366.3696 -407.0604)
		(property "Reference" "R4740"
			(at 0 0 0)
			(layer "F.SilkS")
			(hide yes)
			(effects
				(font
					(size 1.27 1.27)
				)
			)
		)
		(property "Value" ""
			(at 0 0 0)
			(layer "F.Fab")
			(effects
				(font
					(size 1.27 1.27)
				)
			)
		)
		(duplicate_pad_numbers_are_jumpers no)
		(fp_line
			(start -0.7874 -0.4064)
			(end 0.7874 -0.4064)
			(stroke
				(width 0.1524)
				(type default)
			)
			(layer "F.SilkS")
		)
		(fp_line
			(start -0.7874 0.4064)
			(end -0.7874 -0.4064)
			(stroke
				(width 0.1524)
				(type default)
			)
			(layer "F.SilkS")
		)
		(fp_line
			(start 0.7874 -0.4064)
			(end 0.7874 0.4064)
			(stroke
				(width 0.1524)
				(type default)
			)
			(layer "F.SilkS")
		)
		(fp_line
			(start 0.7874 0.4064)
			(end -0.7874 0.4064)
			(stroke
				(width 0.1524)
				(type default)
			)
			(layer "F.SilkS")
		)
		(fp_line
			(start -0.67945 -0.305054)
			(end -0.12065 -0.305054)
			(stroke
				(width 0.1)
				(type default)
			)
			(layer "F.Fab")
		)
		(fp_line
			(start -0.67945 0.3048)
			(end -0.67945 -0.305054)
			(stroke
				(width 0.1)
				(type default)
			)
			(layer "F.Fab")
		)
		(fp_line
			(start -0.12065 -0.305054)
			(end -0.12065 -0.2794)
			(stroke
				(width 0.1)
				(type default)
			)
			(layer "F.Fab")
		)
		(fp_line
			(start -0.12065 -0.2794)
			(end 0.12065 -0.2794)
			(stroke
				(width 0.1)
				(type default)
			)
			(layer "F.Fab")
		)
		(fp_line
			(start -0.12065 0.2794)
			(end -0.12065 0.3048)
			(stroke
				(width 0.1)
				(type default)
			)
			(layer "F.Fab")
		)
		(fp_line
			(start -0.12065 0.3048)
			(end -0.67945 0.3048)
			(stroke
				(width 0.1)
				(type default)
			)
			(layer "F.Fab")
		)
		(fp_line
			(start 0.120396 0.2794)
			(end -0.12065 0.2794)
			(stroke
				(width 0.1)
				(type default)
			)
			(layer "F.Fab")
		)
		(fp_line
			(start 0.120396 0.3048)
			(end 0.120396 0.2794)
			(stroke
				(width 0.1)
				(type default)
			)
			(layer "F.Fab")
		)
		(fp_line
			(start 0.12065 -0.3048)
			(end 0.67945 -0.3048)
			(stroke
				(width 0.1)
				(type default)
			)
			(layer "F.Fab")
		)
		(fp_line
			(start 0.12065 -0.2794)
			(end 0.12065 -0.3048)
			(stroke
				(width 0.1)
				(type default)
			)
			(layer "F.Fab")
		)
		(fp_line
			(start 0.67945 -0.3048)
			(end 0.67945 0.3048)
			(stroke
				(width 0.1)
				(type default)
			)
			(layer "F.Fab")
		)
		(fp_line
			(start 0.67945 0.3048)
			(end 0.120396 0.3048)
			(stroke
				(width 0.1)
				(type default)
			)
			(layer "F.Fab")
		)
		(pad "1" smd circle
			(at -0.40005 0)
			(size 0 0)
			(layers "F.Cu" "F.Mask" "F.Paste")
			(net "P3V3_AUX")
		)
		(pad "2" smd circle
			(at 0.40005 0)
			(size 0 0)
			(layers "F.Cu" "F.Mask" "F.Paste")
			(net "PRSNT_CABLE_SWB_B1_ISO_N")
		)
	)
)
